(kicad_pcb
	(version 20260206)
	(generator "pcbnew")
	(generator_version "10.0")
	(general
		(thickness 1.6)
		(legacy_teardrops no)
	)
	(paper "A4")
	(title_block
		(title "03242023_DA0F0TMBIJ0_F0T_Motherboard_J_brd_V01_OCP.brd")
		(comment 1 "Grand Teton / footprint 1301 of 6105 (J27), pads 113-224 of 291")
	)
	(layers
		(0 "F.Cu" signal "TOP")
		(4 "In1.Cu" signal "GND")
		(6 "In2.Cu" signal "IN1")
		(8 "In3.Cu" signal "GND1")
		(10 "In4.Cu" signal "IN2")
		(12 "In5.Cu" signal "GND2")
		(14 "In6.Cu" signal "IN3")
		(16 "In7.Cu" signal "GND3")
		(18 "In8.Cu" signal "VCC")
		(20 "In9.Cu" signal "VCC1")
		(22 "In10.Cu" signal "GND4")
		(24 "In11.Cu" signal "IN4")
		(26 "In12.Cu" signal "GND5")
		(28 "In13.Cu" signal "IN5")
		(30 "In14.Cu" signal "GND6")
		(32 "In15.Cu" signal "IN6")
		(34 "In16.Cu" signal "GND7")
		(2 "B.Cu" signal "BOTTOM")
		(9 "F.Adhes" user "F.Adhesive")
		(11 "B.Adhes" user "B.Adhesive")
		(13 "F.Paste" user "Package Geometry/Pastemask Top")
		(15 "B.Paste" user "Package Geometry/Pastemask Bottom")
		(5 "F.SilkS" user "Ref Des/Silkscreen Top")
		(7 "B.SilkS" user "Ref Des/Silkscreen Bottom")
		(1 "F.Mask" user "Board Geometry/Soldermask Top")
		(3 "B.Mask" user "Board Geometry/Soldermask Bottom")
		(17 "Dwgs.User" user "User.Drawings")
		(19 "Cmts.User" user "User.Comments")
		(21 "Eco1.User" user "User.Eco1")
		(23 "Eco2.User" user "User.Eco2")
		(25 "Edge.Cuts" user "Board Geometry/Outline")
		(27 "Margin" user)
		(31 "F.CrtYd" user "Package Geometry/Place Bound Top")
		(29 "B.CrtYd" user "Package Geometry/Place Bound Bottom")
		(35 "F.Fab" user "Ref Des/Assembly Top")
		(33 "B.Fab" user "Ref Des/Assembly Bottom")
	)
	(footprint ""
		(layer "F.Cu")
		(at 183.49468 -258.091686)
		(property "Reference" "J27"
			(at 2.19456 -81.755488 0)
			(unlocked yes)
			(layer "F.SilkS")
			(effects
				(font
					(size 0.7874 0.5842)
					(thickness 0.1524)
				)
				(justify left)
			)
		)
		(property "Value" ""
			(at 0 0 0)
			(layer "F.Fab")
			(effects
				(font
					(size 1.27 1.27)
				)
			)
		)
		(duplicate_pad_numbers_are_jumpers no)
		(pad "113" smd rect
			(at -2.050034 36.975034 270)
			(size 0.519938 1.4986)
			(layers "F.Cu" "F.Mask" "F.Paste")
			(net "M_F_CPU1_SB_DQ<9>")
		)
		(pad "114" smd rect
			(at -2.050034 37.824918 270)
			(size 0.519938 1.4986)
			(layers "F.Cu" "F.Mask" "F.Paste")
			(net "GND")
		)
		(pad "115" smd rect
			(at -2.050034 38.675056 270)
			(size 0.519938 1.4986)
			(layers "F.Cu" "F.Mask" "F.Paste")
			(net "M_F_CPU1_SB_DQS_DP<1>")
		)
		(pad "116" smd rect
			(at -2.050034 39.52494 270)
			(size 0.519938 1.4986)
			(layers "F.Cu" "F.Mask" "F.Paste")
			(net "M_F_CPU1_SB_DQS_DN<1>")
		)
		(pad "117" smd rect
			(at -2.050034 40.375078 270)
			(size 0.519938 1.4986)
			(layers "F.Cu" "F.Mask" "F.Paste")
			(net "GND")
		)
		(pad "118" smd rect
			(at -2.050034 41.224962 270)
			(size 0.519938 1.4986)
			(layers "F.Cu" "F.Mask" "F.Paste")
			(net "M_F_CPU1_SB_DQ<12>")
		)
		(pad "119" smd rect
			(at -2.050034 42.0751 270)
			(size 0.519938 1.4986)
			(layers "F.Cu" "F.Mask" "F.Paste")
			(net "GND")
		)
		(pad "120" smd rect
			(at -2.050034 42.924984 270)
			(size 0.519938 1.4986)
			(layers "F.Cu" "F.Mask" "F.Paste")
			(net "M_F_CPU1_SB_DQ<13>")
		)
		(pad "121" smd rect
			(at -2.050034 43.775122 270)
			(size 0.519938 1.4986)
			(layers "F.Cu" "F.Mask" "F.Paste")
			(net "GND")
		)
		(pad "122" smd rect
			(at -2.050034 44.625006 270)
			(size 0.519938 1.4986)
			(layers "F.Cu" "F.Mask" "F.Paste")
			(net "M_F_CPU1_SB_DQ<16>")
		)
		(pad "123" smd rect
			(at -2.050034 45.47489 270)
			(size 0.519938 1.4986)
			(layers "F.Cu" "F.Mask" "F.Paste")
			(net "GND")
		)
		(pad "124" smd rect
			(at -2.050034 46.325028 270)
			(size 0.519938 1.4986)
			(layers "F.Cu" "F.Mask" "F.Paste")
			(net "M_F_CPU1_SB_DQ<17>")
		)
		(pad "125" smd rect
			(at -2.050034 47.174912 270)
			(size 0.519938 1.4986)
			(layers "F.Cu" "F.Mask" "F.Paste")
			(net "GND")
		)
		(pad "126" smd rect
			(at -2.050034 48.02505 270)
			(size 0.519938 1.4986)
			(layers "F.Cu" "F.Mask" "F.Paste")
			(net "M_F_CPU1_SB_DQS_DP<2>")
		)
		(pad "127" smd rect
			(at -2.050034 48.874934 270)
			(size 0.519938 1.4986)
			(layers "F.Cu" "F.Mask" "F.Paste")
			(net "M_F_CPU1_SB_DQS_DN<2>")
		)
		(pad "128" smd rect
			(at -2.050034 49.725072 270)
			(size 0.519938 1.4986)
			(layers "F.Cu" "F.Mask" "F.Paste")
			(net "GND")
		)
		(pad "129" smd rect
			(at -2.050034 50.574956 270)
			(size 0.519938 1.4986)
			(layers "F.Cu" "F.Mask" "F.Paste")
			(net "M_F_CPU1_SB_DQ<20>")
		)
		(pad "130" smd rect
			(at -2.050034 51.425094 270)
			(size 0.519938 1.4986)
			(layers "F.Cu" "F.Mask" "F.Paste")
			(net "GND")
		)
		(pad "131" smd rect
			(at -2.050034 52.274978 270)
			(size 0.519938 1.4986)
			(layers "F.Cu" "F.Mask" "F.Paste")
			(net "M_F_CPU1_SB_DQ<21>")
		)
		(pad "132" smd rect
			(at -2.050034 53.125116 270)
			(size 0.519938 1.4986)
			(layers "F.Cu" "F.Mask" "F.Paste")
			(net "GND")
		)
		(pad "133" smd rect
			(at -2.050034 53.975 270)
			(size 0.519938 1.4986)
			(layers "F.Cu" "F.Mask" "F.Paste")
			(net "M_F_CPU1_SB_DQ<24>")
		)
		(pad "134" smd rect
			(at -2.050034 54.824884 270)
			(size 0.519938 1.4986)
			(layers "F.Cu" "F.Mask" "F.Paste")
			(net "GND")
		)
		(pad "135" smd rect
			(at -2.050034 55.675022 270)
			(size 0.519938 1.4986)
			(layers "F.Cu" "F.Mask" "F.Paste")
			(net "M_F_CPU1_SB_DQ<25>")
		)
		(pad "136" smd rect
			(at -2.050034 56.524906 270)
			(size 0.519938 1.4986)
			(layers "F.Cu" "F.Mask" "F.Paste")
			(net "GND")
		)
		(pad "137" smd rect
			(at -2.050034 57.375044 270)
			(size 0.519938 1.4986)
			(layers "F.Cu" "F.Mask" "F.Paste")
			(net "M_F_CPU1_SB_DQS_DP<3>")
		)
		(pad "138" smd rect
			(at -2.050034 58.224928 270)
			(size 0.519938 1.4986)
			(layers "F.Cu" "F.Mask" "F.Paste")
			(net "M_F_CPU1_SB_DQS_DN<3>")
		)
		(pad "139" smd rect
			(at -2.050034 59.075066 270)
			(size 0.519938 1.4986)
			(layers "F.Cu" "F.Mask" "F.Paste")
			(net "GND")
		)
		(pad "140" smd rect
			(at -2.050034 59.92495 270)
			(size 0.519938 1.4986)
			(layers "F.Cu" "F.Mask" "F.Paste")
			(net "M_F_CPU1_SB_DQ<28>")
		)
		(pad "141" smd rect
			(at -2.050034 60.775088 270)
			(size 0.519938 1.4986)
			(layers "F.Cu" "F.Mask" "F.Paste")
			(net "GND")
		)
		(pad "142" smd rect
			(at -2.050034 61.624972 270)
			(size 0.519938 1.4986)
			(layers "F.Cu" "F.Mask" "F.Paste")
			(net "M_F_CPU1_SB_DQ<29>")
		)
		(pad "143" smd rect
			(at -2.050034 62.47511 270)
			(size 0.519938 1.4986)
			(layers "F.Cu" "F.Mask" "F.Paste")
			(net "GND")
		)
		(pad "144" smd rect
			(at -2.050034 63.324994 270)
			(size 0.519938 1.4986)
			(layers "F.Cu" "F.Mask" "F.Paste")
			(net "TP_CHF_CPU1_DIMM1_FRU_1")
		)
		(pad "145" smd rect
			(at 2.050034 -63.324994 270)
			(size 0.519938 1.4986)
			(layers "F.Cu" "F.Mask" "F.Paste")
			(net "P12V_S3_AUX_CPU1_NVDIMM")
		)
		(pad "146" smd rect
			(at 2.050034 -62.47511 270)
			(size 0.519938 1.4986)
			(layers "F.Cu" "F.Mask" "F.Paste")
			(net "P12V_S3_AUX_CPU1_NVDIMM")
		)
		(pad "147" smd rect
			(at 2.050034 -61.624972 270)
			(size 0.519938 1.4986)
			(layers "F.Cu" "F.Mask" "F.Paste")
			(net "PWRGD_CHF_CPU1_DIMM1")
		)
		(pad "148" smd rect
			(at 2.050034 -60.775088 270)
			(size 0.519938 1.4986)
			(layers "F.Cu" "F.Mask" "F.Paste")
			(net "PD_CHF_CPU1_DIMM1_SAA")
		)
		(pad "149" smd rect
			(at 2.050034 -59.92495 270)
			(size 0.519938 1.4986)
			(layers "F.Cu" "F.Mask" "F.Paste")
			(net "TP_CHF_CPU1_DIMM1_FRU_2")
		)
		(pad "150" smd rect
			(at 2.050034 -59.075066 270)
			(size 0.519938 1.4986)
			(layers "F.Cu" "F.Mask" "F.Paste")
			(net "TP_CHF_CPU1_DIMM1_FRU_3")
		)
		(pad "151" smd rect
			(at 2.050034 -58.224928 270)
			(size 0.519938 1.4986)
			(layers "F.Cu" "F.Mask" "F.Paste")
			(net "GND")
		)
		(pad "152" smd rect
			(at 2.050034 -57.375044 270)
			(size 0.519938 1.4986)
			(layers "F.Cu" "F.Mask" "F.Paste")
			(net "M_F_CPU1_SA_DQ<2>")
		)
		(pad "153" smd rect
			(at 2.050034 -56.524906 270)
			(size 0.519938 1.4986)
			(layers "F.Cu" "F.Mask" "F.Paste")
			(net "GND")
		)
		(pad "154" smd rect
			(at 2.050034 -55.675022 270)
			(size 0.519938 1.4986)
			(layers "F.Cu" "F.Mask" "F.Paste")
			(net "M_F_CPU1_SA_DQ<3>")
		)
		(pad "155" smd rect
			(at 2.050034 -54.824884 270)
			(size 0.519938 1.4986)
			(layers "F.Cu" "F.Mask" "F.Paste")
			(net "GND")
		)
		(pad "156" smd rect
			(at 2.050034 -53.975 270)
			(size 0.519938 1.4986)
			(layers "F.Cu" "F.Mask" "F.Paste")
			(net "M_F_CPU1_SA_DQS_DN<5>")
		)
		(pad "157" smd rect
			(at 2.050034 -53.125116 270)
			(size 0.519938 1.4986)
			(layers "F.Cu" "F.Mask" "F.Paste")
			(net "M_F_CPU1_SA_DQS_DP<5>")
		)
		(pad "158" smd rect
			(at 2.050034 -52.274978 270)
			(size 0.519938 1.4986)
			(layers "F.Cu" "F.Mask" "F.Paste")
			(net "GND")
		)
		(pad "159" smd rect
			(at 2.050034 -51.425094 270)
			(size 0.519938 1.4986)
			(layers "F.Cu" "F.Mask" "F.Paste")
			(net "M_F_CPU1_SA_DQ<6>")
		)
		(pad "160" smd rect
			(at 2.050034 -50.574956 270)
			(size 0.519938 1.4986)
			(layers "F.Cu" "F.Mask" "F.Paste")
			(net "GND")
		)
		(pad "161" smd rect
			(at 2.050034 -49.725072 270)
			(size 0.519938 1.4986)
			(layers "F.Cu" "F.Mask" "F.Paste")
			(net "M_F_CPU1_SA_DQ<7>")
		)
		(pad "162" smd rect
			(at 2.050034 -48.874934 270)
			(size 0.519938 1.4986)
			(layers "F.Cu" "F.Mask" "F.Paste")
			(net "GND")
		)
		(pad "163" smd rect
			(at 2.050034 -48.02505 270)
			(size 0.519938 1.4986)
			(layers "F.Cu" "F.Mask" "F.Paste")
			(net "M_F_CPU1_SA_DQ<10>")
		)
		(pad "164" smd rect
			(at 2.050034 -47.174912 270)
			(size 0.519938 1.4986)
			(layers "F.Cu" "F.Mask" "F.Paste")
			(net "GND")
		)
		(pad "165" smd rect
			(at 2.050034 -46.325028 270)
			(size 0.519938 1.4986)
			(layers "F.Cu" "F.Mask" "F.Paste")
			(net "M_F_CPU1_SA_DQ<11>")
		)
		(pad "166" smd rect
			(at 2.050034 -45.47489 270)
			(size 0.519938 1.4986)
			(layers "F.Cu" "F.Mask" "F.Paste")
			(net "GND")
		)
		(pad "167" smd rect
			(at 2.050034 -44.625006 270)
			(size 0.519938 1.4986)
			(layers "F.Cu" "F.Mask" "F.Paste")
			(net "M_F_CPU1_SA_DQS_DN<6>")
		)
		(pad "168" smd rect
			(at 2.050034 -43.775122 270)
			(size 0.519938 1.4986)
			(layers "F.Cu" "F.Mask" "F.Paste")
			(net "M_F_CPU1_SA_DQS_DP<6>")
		)
		(pad "169" smd rect
			(at 2.050034 -42.924984 270)
			(size 0.519938 1.4986)
			(layers "F.Cu" "F.Mask" "F.Paste")
			(net "GND")
		)
		(pad "170" smd rect
			(at 2.050034 -42.0751 270)
			(size 0.519938 1.4986)
			(layers "F.Cu" "F.Mask" "F.Paste")
			(net "M_F_CPU1_SA_DQ<14>")
		)
		(pad "171" smd rect
			(at 2.050034 -41.224962 270)
			(size 0.519938 1.4986)
			(layers "F.Cu" "F.Mask" "F.Paste")
			(net "GND")
		)
		(pad "172" smd rect
			(at 2.050034 -40.375078 270)
			(size 0.519938 1.4986)
			(layers "F.Cu" "F.Mask" "F.Paste")
			(net "M_F_CPU1_SA_DQ<15>")
		)
		(pad "173" smd rect
			(at 2.050034 -39.52494 270)
			(size 0.519938 1.4986)
			(layers "F.Cu" "F.Mask" "F.Paste")
			(net "GND")
		)
		(pad "174" smd rect
			(at 2.050034 -38.675056 270)
			(size 0.519938 1.4986)
			(layers "F.Cu" "F.Mask" "F.Paste")
			(net "M_F_CPU1_SA_DQ<18>")
		)
		(pad "175" smd rect
			(at 2.050034 -37.824918 270)
			(size 0.519938 1.4986)
			(layers "F.Cu" "F.Mask" "F.Paste")
			(net "GND")
		)
		(pad "176" smd rect
			(at 2.050034 -36.975034 270)
			(size 0.519938 1.4986)
			(layers "F.Cu" "F.Mask" "F.Paste")
			(net "M_F_CPU1_SA_DQ<19>")
		)
		(pad "177" smd rect
			(at 2.050034 -36.124896 270)
			(size 0.519938 1.4986)
			(layers "F.Cu" "F.Mask" "F.Paste")
			(net "GND")
		)
		(pad "178" smd rect
			(at 2.050034 -35.275012 270)
			(size 0.519938 1.4986)
			(layers "F.Cu" "F.Mask" "F.Paste")
			(net "M_F_CPU1_SA_DQS_DN<7>")
		)
		(pad "179" smd rect
			(at 2.050034 -34.425128 270)
			(size 0.519938 1.4986)
			(layers "F.Cu" "F.Mask" "F.Paste")
			(net "M_F_CPU1_SA_DQS_DP<7>")
		)
		(pad "180" smd rect
			(at 2.050034 -33.57499 270)
			(size 0.519938 1.4986)
			(layers "F.Cu" "F.Mask" "F.Paste")
			(net "GND")
		)
		(pad "181" smd rect
			(at 2.050034 -32.725106 270)
			(size 0.519938 1.4986)
			(layers "F.Cu" "F.Mask" "F.Paste")
			(net "M_F_CPU1_SA_DQ<22>")
		)
		(pad "182" smd rect
			(at 2.050034 -31.874968 270)
			(size 0.519938 1.4986)
			(layers "F.Cu" "F.Mask" "F.Paste")
			(net "GND")
		)
		(pad "183" smd rect
			(at 2.050034 -31.025084 270)
			(size 0.519938 1.4986)
			(layers "F.Cu" "F.Mask" "F.Paste")
			(net "M_F_CPU1_SA_DQ<23>")
		)
		(pad "184" smd rect
			(at 2.050034 -30.174946 270)
			(size 0.519938 1.4986)
			(layers "F.Cu" "F.Mask" "F.Paste")
			(net "GND")
		)
		(pad "185" smd rect
			(at 2.050034 -29.325062 270)
			(size 0.519938 1.4986)
			(layers "F.Cu" "F.Mask" "F.Paste")
			(net "M_F_CPU1_SA_DQ<26>")
		)
		(pad "186" smd rect
			(at 2.050034 -28.474924 270)
			(size 0.519938 1.4986)
			(layers "F.Cu" "F.Mask" "F.Paste")
			(net "GND")
		)
		(pad "187" smd rect
			(at 2.050034 -27.62504 270)
			(size 0.519938 1.4986)
			(layers "F.Cu" "F.Mask" "F.Paste")
			(net "M_F_CPU1_SA_DQ<27>")
		)
		(pad "188" smd rect
			(at 2.050034 -26.774902 270)
			(size 0.519938 1.4986)
			(layers "F.Cu" "F.Mask" "F.Paste")
			(net "GND")
		)
		(pad "189" smd rect
			(at 2.050034 -25.925018 270)
			(size 0.519938 1.4986)
			(layers "F.Cu" "F.Mask" "F.Paste")
			(net "M_F_CPU1_SA_DQS_DN<8>")
		)
		(pad "190" smd rect
			(at 2.050034 -25.07488 270)
			(size 0.519938 1.4986)
			(layers "F.Cu" "F.Mask" "F.Paste")
			(net "M_F_CPU1_SA_DQS_DP<8>")
		)
		(pad "191" smd rect
			(at 2.050034 -24.224996 270)
			(size 0.519938 1.4986)
			(layers "F.Cu" "F.Mask" "F.Paste")
			(net "GND")
		)
		(pad "192" smd rect
			(at 2.050034 -23.375112 270)
			(size 0.519938 1.4986)
			(layers "F.Cu" "F.Mask" "F.Paste")
			(net "M_F_CPU1_SA_DQ<30>")
		)
		(pad "193" smd rect
			(at 2.050034 -22.524974 270)
			(size 0.519938 1.4986)
			(layers "F.Cu" "F.Mask" "F.Paste")
			(net "GND")
		)
		(pad "194" smd rect
			(at 2.050034 -21.67509 270)
			(size 0.519938 1.4986)
			(layers "F.Cu" "F.Mask" "F.Paste")
			(net "M_F_CPU1_SA_DQ<31>")
		)
		(pad "195" smd rect
			(at 2.050034 -20.824952 270)
			(size 0.519938 1.4986)
			(layers "F.Cu" "F.Mask" "F.Paste")
			(net "GND")
		)
		(pad "196" smd rect
			(at 2.050034 -19.975068 270)
			(size 0.519938 1.4986)
			(layers "F.Cu" "F.Mask" "F.Paste")
			(net "M_F_CPU1_SA_CB<2>")
		)
		(pad "197" smd rect
			(at 2.050034 -19.12493 270)
			(size 0.519938 1.4986)
			(layers "F.Cu" "F.Mask" "F.Paste")
			(net "GND")
		)
		(pad "198" smd rect
			(at 2.050034 -18.275046 270)
			(size 0.519938 1.4986)
			(layers "F.Cu" "F.Mask" "F.Paste")
			(net "M_F_CPU1_SA_CB<3>")
		)
		(pad "199" smd rect
			(at 2.050034 -17.424908 270)
			(size 0.519938 1.4986)
			(layers "F.Cu" "F.Mask" "F.Paste")
			(net "GND")
		)
		(pad "200" smd rect
			(at 2.050034 -16.575024 270)
			(size 0.519938 1.4986)
			(layers "F.Cu" "F.Mask" "F.Paste")
			(net "M_F_CPU1_SA_DQS_DN<9>")
		)
		(pad "201" smd rect
			(at 2.050034 -15.724886 270)
			(size 0.519938 1.4986)
			(layers "F.Cu" "F.Mask" "F.Paste")
			(net "M_F_CPU1_SA_DQS_DP<9>")
		)
		(pad "202" smd rect
			(at 2.050034 -14.875002 270)
			(size 0.519938 1.4986)
			(layers "F.Cu" "F.Mask" "F.Paste")
			(net "GND")
		)
		(pad "203" smd rect
			(at 2.050034 -14.025118 270)
			(size 0.519938 1.4986)
			(layers "F.Cu" "F.Mask" "F.Paste")
			(net "M_F_CPU1_SA_CB<6>")
		)
		(pad "204" smd rect
			(at 2.050034 -13.17498 270)
			(size 0.519938 1.4986)
			(layers "F.Cu" "F.Mask" "F.Paste")
			(net "GND")
		)
		(pad "205" smd rect
			(at 2.050034 -12.325096 270)
			(size 0.519938 1.4986)
			(layers "F.Cu" "F.Mask" "F.Paste")
			(net "M_F_CPU1_SA_CB<7>")
		)
		(pad "206" smd rect
			(at 2.050034 -11.474958 270)
			(size 0.519938 1.4986)
			(layers "F.Cu" "F.Mask" "F.Paste")
			(net "GND")
		)
		(pad "207" smd rect
			(at 2.050034 -10.625074 270)
			(size 0.519938 1.4986)
			(layers "F.Cu" "F.Mask" "F.Paste")
			(net "RST_M_EF_CPU1_FPGA_N")
		)
		(pad "208" smd rect
			(at 2.050034 -9.774936 270)
			(size 0.519938 1.4986)
			(layers "F.Cu" "F.Mask" "F.Paste")
			(net "GND")
		)
		(pad "209" smd rect
			(at 2.050034 -8.925052 270)
			(size 0.519938 1.4986)
			(layers "F.Cu" "F.Mask" "F.Paste")
			(net "M_F_CPU1_SA_CS_N<1>")
		)
		(pad "210" smd rect
			(at 2.050034 -8.074914 270)
			(size 0.519938 1.4986)
			(layers "F.Cu" "F.Mask" "F.Paste")
			(net "GND")
		)
		(pad "211" smd rect
			(at 2.050034 -7.22503 270)
			(size 0.519938 1.4986)
			(layers "F.Cu" "F.Mask" "F.Paste")
			(net "M_F_CPU1_SA_CA<1>")
		)
		(pad "212" smd rect
			(at 2.050034 -6.374892 270)
			(size 0.519938 1.4986)
			(layers "F.Cu" "F.Mask" "F.Paste")
			(net "GND")
		)
		(pad "213" smd rect
			(at 2.050034 -5.525008 270)
			(size 0.519938 1.4986)
			(layers "F.Cu" "F.Mask" "F.Paste")
			(net "M_F_CPU1_SA_CA<3>")
		)
		(pad "214" smd rect
			(at 2.050034 -4.675124 270)
			(size 0.519938 1.4986)
			(layers "F.Cu" "F.Mask" "F.Paste")
			(net "GND")
		)
		(pad "215" smd rect
			(at 2.050034 -3.824986 270)
			(size 0.519938 1.4986)
			(layers "F.Cu" "F.Mask" "F.Paste")
			(net "M_F_CPU1_SA_CA<5>")
		)
		(pad "216" smd rect
			(at 2.050034 -2.975102 270)
			(size 0.519938 1.4986)
			(layers "F.Cu" "F.Mask" "F.Paste")
			(net "GND")
		)
		(pad "217" smd rect
			(at 2.050034 -2.124964 270)
			(size 0.519938 1.4986)
			(layers "F.Cu" "F.Mask" "F.Paste")
			(net "M_F_CPU1_CLK_DP<0>")
		)
		(pad "218" smd rect
			(at 2.050034 -1.27508 270)
			(size 0.519938 1.4986)
			(layers "F.Cu" "F.Mask" "F.Paste")
			(net "M_F_CPU1_CLK_DN<0>")
		)
		(pad "219" smd rect
			(at 2.050034 -0.424942 270)
			(size 0.519938 1.4986)
			(layers "F.Cu" "F.Mask" "F.Paste")
			(net "GND")
		)
		(pad "220" smd rect
			(at 2.050034 5.525008 270)
			(size 0.519938 1.4986)
			(layers "F.Cu" "F.Mask" "F.Paste")
			(net "TP_CHF_CPU1_DIMM1_FRU_4")
		)
		(pad "221" smd rect
			(at 2.050034 6.374892 270)
			(size 0.519938 1.4986)
			(layers "F.Cu" "F.Mask" "F.Paste")
			(net "M_F_CPU1_SB_CA<1>")
		)
		(pad "222" smd rect
			(at 2.050034 7.22503 270)
			(size 0.519938 1.4986)
			(layers "F.Cu" "F.Mask" "F.Paste")
			(net "GND")
		)
		(pad "223" smd rect
			(at 2.050034 8.074914 270)
			(size 0.519938 1.4986)
			(layers "F.Cu" "F.Mask" "F.Paste")
			(net "M_F_CPU1_SB_CA<3>")
		)
		(pad "224" smd rect
			(at 2.050034 8.925052 270)
			(size 0.519938 1.4986)
			(layers "F.Cu" "F.Mask" "F.Paste")
			(net "GND")
		)
	)
)
